(kicad_pcb
	(version 20260206)
	(generator "pcbnew")
	(generator_version "10.0")
	(general
		(thickness 1.6)
		(legacy_teardrops no)
	)
	(paper "A4")
	(title_block
		(title "peb — Lightning_PEB_BRD.brd")
		(comment 1 "Lightning (Wiwynn / Facebook NVMe JBOF) / footprints 2216-2223 of 2563")
	)
	(layers
		(0 "F.Cu" signal "TOP")
		(4 "In1.Cu" signal "L2GND")
		(6 "In2.Cu" signal "L3")
		(8 "In3.Cu" signal "L4VCC")
		(10 "In4.Cu" signal "L5VCC")
		(12 "In5.Cu" signal "L6")
		(14 "In6.Cu" signal "L7GND")
		(2 "B.Cu" signal "BOTTOM")
		(9 "F.Adhes" user "F.Adhesive")
		(11 "B.Adhes" user "B.Adhesive")
		(13 "F.Paste" user "Package Geometry/Pastemask Top")
		(15 "B.Paste" user "Package Geometry/Pastemask Bottom")
		(5 "F.SilkS" user "Ref Des/Silkscreen Top")
		(7 "B.SilkS" user "Ref Des/Silkscreen Bottom")
		(1 "F.Mask" user "Board Geometry/Soldermask Top")
		(3 "B.Mask" user "Board Geometry/Soldermask Bottom")
		(17 "Dwgs.User" user "User.Drawings")
		(19 "Cmts.User" user "User.Comments")
		(21 "Eco1.User" user "User.Eco1")
		(23 "Eco2.User" user "User.Eco2")
		(25 "Edge.Cuts" user "Board Geometry/Outline")
		(27 "Margin" user)
		(31 "F.CrtYd" user "Package Geometry/Place Bound Top")
		(29 "B.CrtYd" user "Package Geometry/Place Bound Bottom")
		(35 "F.Fab" user "Ref Des/Assembly Top")
		(33 "B.Fab" user "Ref Des/Assembly Bottom")
	)
	(footprint ""
		(layer "B.Cu")
		(at 252.603 -44.010072 -90)
		(property "Reference" "C614"
			(at 0 0 90)
			(layer "B.SilkS")
			(hide yes)
			(effects
				(font
					(size 1.27 1.27)
				)
				(justify mirror)
			)
		)
		(property "Value" "SCD1U16V1KX-1-GP"
			(at 2.8321 -1.7399 270)
			(unlocked yes)
			(layer "B.Fab")
			(hide yes)
			(effects
				(font
					(size 1.016 1.016)
					(thickness 0.1524)
				)
				(justify mirror)
			)
		)
		(property "Device Type" "C0201H13"
			(at 2.8321 -3.2639 270)
			(unlocked yes)
			(layer "B.Fab")
			(hide yes)
			(effects
				(font
					(size 1.016 1.016)
					(thickness 0.1524)
				)
				(justify mirror)
			)
		)
		(duplicate_pad_numbers_are_jumpers no)
		(fp_rect
			(start 0.2794 0.6477)
			(end -0.2794 -0.6477)
			(stroke
				(width 0)
				(type default)
			)
			(fill no)
			(layer "B.CrtYd")
		)
		(fp_rect
			(start 0.2794 0.6477)
			(end -0.2794 -0.6477)
			(stroke
				(width 0)
				(type default)
			)
			(fill no)
			(layer "B.Fab")
		)
		(pad "1" smd custom
			(at 0 -0.2794 90)
			(size 0.0762 0.0762)
			(layers "B.Cu" "B.Mask" "B.Paste")
			(net "DUT_AVD_PCIE")
			(options
				(clearance outline)
				(anchor circle)
			)
			(primitives
				(gr_poly
					(pts
						(arc
							(start 0.1524 0.127)
							(mid 0.137521 0.162921)
							(end 0.1016 0.1778)
						)
						(arc
							(start -0.1016 0.1778)
							(mid -0.137521 0.162921)
							(end -0.1524 0.127)
						)
						(arc
							(start -0.1524 -0.127)
							(mid -0.137521 -0.162921)
							(end -0.1016 -0.1778)
						)
						(arc
							(start 0.1016 -0.1778)
							(mid 0.137521 -0.162921)
							(end 0.1524 -0.127)
						)
					)
					(width 0)
					(fill yes)
				)
			)
		)
		(pad "2" smd custom
			(at 0 0.2794 90)
			(size 0.0762 0.0762)
			(layers "B.Cu" "B.Mask" "B.Paste")
			(net "GND")
			(options
				(clearance outline)
				(anchor circle)
			)
			(primitives
				(gr_poly
					(pts
						(arc
							(start 0.1524 0.127)
							(mid 0.137521 0.162921)
							(end 0.1016 0.1778)
						)
						(arc
							(start -0.1016 0.1778)
							(mid -0.137521 0.162921)
							(end -0.1524 0.127)
						)
						(arc
							(start -0.1524 -0.127)
							(mid -0.137521 -0.162921)
							(end -0.1016 -0.1778)
						)
						(arc
							(start 0.1016 -0.1778)
							(mid 0.137521 -0.162921)
							(end 0.1524 -0.127)
						)
					)
					(width 0)
					(fill yes)
				)
			)
		)
	)
	(footprint ""
		(layer "B.Cu")
		(at 67.945 -190.627)
		(property "Reference" "R210"
			(at 0 0 0)
			(layer "B.SilkS")
			(hide yes)
			(effects
				(font
					(size 1.27 1.27)
				)
				(justify mirror)
			)
		)
		(property "Value" "4K7R2F-GP"
			(at -0.064008 -3.993896 0)
			(unlocked yes)
			(layer "B.Fab")
			(hide yes)
			(effects
				(font
					(size 1.016 1.016)
					(thickness 0.1524)
				)
				(justify mirror)
			)
		)
		(property "Device Type" "R402H16"
			(at -0.064008 -5.517896 0)
			(unlocked yes)
			(layer "B.Fab")
			(hide yes)
			(effects
				(font
					(size 1.016 1.016)
					(thickness 0.1524)
				)
				(justify mirror)
			)
		)
		(duplicate_pad_numbers_are_jumpers no)
		(fp_line
			(start -0.508 -0.9398)
			(end 0.508 -0.9398)
			(stroke
				(width 0.1524)
				(type default)
			)
			(layer "B.SilkS")
		)
		(fp_line
			(start 0.508 -0.9398)
			(end 0.508 0.9398)
			(stroke
				(width 0.1524)
				(type default)
			)
			(layer "B.SilkS")
		)
		(fp_rect
			(start 0.508 0.9398)
			(end -0.508 -0.9398)
			(stroke
				(width 0)
				(type default)
			)
			(fill no)
			(layer "B.CrtYd")
		)
		(fp_rect
			(start 0.508 0.9398)
			(end -0.508 -0.9398)
			(stroke
				(width 0)
				(type default)
			)
			(fill no)
			(layer "B.Fab")
		)
		(pad "1" smd custom
			(at 0 -0.4445 180)
			(size 0.1397 0.1397)
			(layers "B.Cu" "B.Mask" "B.Paste")
			(net "BMC_SSD_RST#0_A11")
			(options
				(clearance outline)
				(anchor circle)
			)
			(primitives
				(gr_poly
					(pts
						(arc
							(start -0.1778 0.2794)
							(mid -0.249642 0.249642)
							(end -0.2794 0.1778)
						)
						(arc
							(start -0.2794 -0.1778)
							(mid -0.249642 -0.249642)
							(end -0.1778 -0.2794)
						)
						(arc
							(start 0.1778 -0.2794)
							(mid 0.249642 -0.249642)
							(end 0.2794 -0.1778)
						)
						(arc
							(start 0.2794 0.1778)
							(mid 0.249642 0.249642)
							(end 0.1778 0.2794)
						)
					)
					(width 0)
					(fill yes)
				)
			)
		)
		(pad "2" smd custom
			(at 0 0.4445 180)
			(size 0.1397 0.1397)
			(layers "B.Cu" "B.Mask" "B.Paste")
			(net "P3V3_STBY")
			(options
				(clearance outline)
				(anchor circle)
			)
			(primitives
				(gr_poly
					(pts
						(arc
							(start -0.1778 0.2794)
							(mid -0.249642 0.249642)
							(end -0.2794 0.1778)
						)
						(arc
							(start -0.2794 -0.1778)
							(mid -0.249642 -0.249642)
							(end -0.1778 -0.2794)
						)
						(arc
							(start 0.1778 -0.2794)
							(mid 0.249642 -0.249642)
							(end 0.2794 -0.1778)
						)
						(arc
							(start 0.2794 0.1778)
							(mid 0.249642 0.249642)
							(end 0.1778 0.2794)
						)
					)
					(width 0)
					(fill yes)
				)
			)
		)
	)
	(footprint ""
		(layer "B.Cu")
		(at 230.63708 -38.94836 -90)
		(property "Reference" "TP278"
			(at 0 0 90)
			(layer "B.SilkS")
			(hide yes)
			(effects
				(font
					(size 1.27 1.27)
				)
				(justify mirror)
			)
		)
		(property "Value" "TPAD28-2-GP"
			(at 0.0127 -1.6637 270)
			(unlocked yes)
			(layer "B.Fab")
			(hide yes)
			(effects
				(font
					(size 1.016 1.016)
					(thickness 0.1524)
				)
				(justify mirror)
			)
		)
		(property "Device Type" "TPAD28"
			(at 0.0127 -3.1877 270)
			(unlocked yes)
			(layer "B.Fab")
			(hide yes)
			(effects
				(font
					(size 1.016 1.016)
					(thickness 0.1524)
				)
				(justify mirror)
			)
		)
		(duplicate_pad_numbers_are_jumpers no)
		(fp_poly
			(pts
				(arc
					(start 0 -0.3556)
					(mid 0 0.3556)
					(end 0 -0.3556)
				)
			)
			(stroke
				(width 0)
				(type default)
			)
			(fill no)
			(layer "B.CrtYd")
		)
		(fp_poly
			(pts
				(arc
					(start 0 -0.6096)
					(mid 0 0.6096)
					(end 0 -0.6096)
				)
			)
			(stroke
				(width 0)
				(type default)
			)
			(fill no)
			(layer "B.Fab")
		)
		(pad "1" smd circle
			(at 0 0 90)
			(size 0.7112 0.7112)
			(layers "B.Cu" "B.Mask" "B.Paste")
			(net "SPI_CSB0_1")
		)
	)
	(footprint ""
		(layer "B.Cu")
		(at 22.987 -69.58076 90)
		(property "Reference" "R396"
			(at 0 0 90)
			(layer "B.SilkS")
			(hide yes)
			(effects
				(font
					(size 1.27 1.27)
				)
				(justify mirror)
			)
		)
		(property "Value" "100KR2J-1-GP"
			(at -0.064008 -3.993896 90)
			(unlocked yes)
			(layer "B.Fab")
			(hide yes)
			(effects
				(font
					(size 1.016 1.016)
					(thickness 0.1524)
				)
				(justify mirror)
			)
		)
		(property "Device Type" "R402H16"
			(at -0.064008 -5.517896 90)
			(unlocked yes)
			(layer "B.Fab")
			(hide yes)
			(effects
				(font
					(size 1.016 1.016)
					(thickness 0.1524)
				)
				(justify mirror)
			)
		)
		(duplicate_pad_numbers_are_jumpers no)
		(fp_line
			(start 0.508 -0.9398)
			(end 0.508 0.9398)
			(stroke
				(width 0.1524)
				(type default)
			)
			(layer "B.SilkS")
		)
		(fp_line
			(start -0.508 -0.9398)
			(end 0.508 -0.9398)
			(stroke
				(width 0.1524)
				(type default)
			)
			(layer "B.SilkS")
		)
		(fp_rect
			(start 0.508 0.9398)
			(end -0.508 -0.9398)
			(stroke
				(width 0)
				(type default)
			)
			(fill no)
			(layer "B.CrtYd")
		)
		(fp_rect
			(start 0.508 0.9398)
			(end -0.508 -0.9398)
			(stroke
				(width 0)
				(type default)
			)
			(fill no)
			(layer "B.Fab")
		)
		(pad "1" smd custom
			(at 0 -0.4445 270)
			(size 0.1397 0.1397)
			(layers "B.Cu" "B.Mask" "B.Paste")
			(net "P3V3_STBY")
			(options
				(clearance outline)
				(anchor circle)
			)
			(primitives
				(gr_poly
					(pts
						(arc
							(start -0.1778 0.2794)
							(mid -0.249642 0.249642)
							(end -0.2794 0.1778)
						)
						(arc
							(start -0.2794 -0.1778)
							(mid -0.249642 -0.249642)
							(end -0.1778 -0.2794)
						)
						(arc
							(start 0.1778 -0.2794)
							(mid 0.249642 -0.249642)
							(end 0.2794 -0.1778)
						)
						(arc
							(start 0.2794 0.1778)
							(mid 0.249642 0.249642)
							(end 0.1778 0.2794)
						)
					)
					(width 0)
					(fill yes)
				)
			)
		)
		(pad "2" smd custom
			(at 0 0.4445 270)
			(size 0.1397 0.1397)
			(layers "B.Cu" "B.Mask" "B.Paste")
			(net "PHY_RESET_N")
			(options
				(clearance outline)
				(anchor circle)
			)
			(primitives
				(gr_poly
					(pts
						(arc
							(start -0.1778 0.2794)
							(mid -0.249642 0.249642)
							(end -0.2794 0.1778)
						)
						(arc
							(start -0.2794 -0.1778)
							(mid -0.249642 -0.249642)
							(end -0.1778 -0.2794)
						)
						(arc
							(start 0.1778 -0.2794)
							(mid 0.249642 -0.249642)
							(end 0.2794 -0.1778)
						)
						(arc
							(start 0.2794 0.1778)
							(mid 0.249642 0.249642)
							(end 0.1778 0.2794)
						)
					)
					(width 0)
					(fill yes)
				)
			)
		)
	)
	(footprint ""
		(layer "B.Cu")
		(at 20.955 -129.667 90)
		(property "Reference" "R340"
			(at 0 0 90)
			(layer "B.SilkS")
			(hide yes)
			(effects
				(font
					(size 1.27 1.27)
				)
				(justify mirror)
			)
		)
		(property "Value" "3K3R2F-2-GP"
			(at -0.064008 -3.993896 90)
			(unlocked yes)
			(layer "B.Fab")
			(hide yes)
			(effects
				(font
					(size 1.016 1.016)
					(thickness 0.1524)
				)
				(justify mirror)
			)
		)
		(property "Device Type" "R402H16"
			(at -0.064008 -5.517896 90)
			(unlocked yes)
			(layer "B.Fab")
			(hide yes)
			(effects
				(font
					(size 1.016 1.016)
					(thickness 0.1524)
				)
				(justify mirror)
			)
		)
		(duplicate_pad_numbers_are_jumpers no)
		(fp_line
			(start 0.508 -0.9398)
			(end 0.508 0.9398)
			(stroke
				(width 0.1524)
				(type default)
			)
			(layer "B.SilkS")
		)
		(fp_line
			(start -0.508 -0.9398)
			(end 0.508 -0.9398)
			(stroke
				(width 0.1524)
				(type default)
			)
			(layer "B.SilkS")
		)
		(fp_rect
			(start 0.508 0.9398)
			(end -0.508 -0.9398)
			(stroke
				(width 0)
				(type default)
			)
			(fill no)
			(layer "B.CrtYd")
		)
		(fp_rect
			(start 0.508 0.9398)
			(end -0.508 -0.9398)
			(stroke
				(width 0)
				(type default)
			)
			(fill no)
			(layer "B.Fab")
		)
		(pad "1" smd custom
			(at 0 -0.4445 270)
			(size 0.1397 0.1397)
			(layers "B.Cu" "B.Mask" "B.Paste")
			(net "P3V3_STBY")
			(options
				(clearance outline)
				(anchor circle)
			)
			(primitives
				(gr_poly
					(pts
						(arc
							(start -0.1778 0.2794)
							(mid -0.249642 0.249642)
							(end -0.2794 0.1778)
						)
						(arc
							(start -0.2794 -0.1778)
							(mid -0.249642 -0.249642)
							(end -0.1778 -0.2794)
						)
						(arc
							(start 0.1778 -0.2794)
							(mid 0.249642 -0.249642)
							(end 0.2794 -0.1778)
						)
						(arc
							(start 0.2794 0.1778)
							(mid 0.249642 0.249642)
							(end 0.1778 0.2794)
						)
					)
					(width 0)
					(fill yes)
				)
			)
		)
		(pad "2" smd custom
			(at 0 0.4445 270)
			(size 0.1397 0.1397)
			(layers "B.Cu" "B.Mask" "B.Paste")
			(net "ROMA8")
			(options
				(clearance outline)
				(anchor circle)
			)
			(primitives
				(gr_poly
					(pts
						(arc
							(start -0.1778 0.2794)
							(mid -0.249642 0.249642)
							(end -0.2794 0.1778)
						)
						(arc
							(start -0.2794 -0.1778)
							(mid -0.249642 -0.249642)
							(end -0.1778 -0.2794)
						)
						(arc
							(start 0.1778 -0.2794)
							(mid 0.249642 -0.249642)
							(end 0.2794 -0.1778)
						)
						(arc
							(start 0.2794 0.1778)
							(mid 0.249642 0.249642)
							(end 0.1778 0.2794)
						)
					)
					(width 0)
					(fill yes)
				)
			)
		)
	)
	(footprint ""
		(layer "B.Cu")
		(at 41.656 -116.713 180)
		(property "Reference" "R672"
			(at 0 0 0)
			(layer "B.SilkS")
			(hide yes)
			(effects
				(font
					(size 1.27 1.27)
				)
				(justify mirror)
			)
		)
		(property "Value" "0R2J-2-GP"
			(at -0.064008 -3.993896 180)
			(unlocked yes)
			(layer "B.Fab")
			(hide yes)
			(effects
				(font
					(size 1.016 1.016)
					(thickness 0.1524)
				)
				(justify mirror)
			)
		)
		(property "Device Type" "R402H16"
			(at -0.064008 -5.517896 180)
			(unlocked yes)
			(layer "B.Fab")
			(hide yes)
			(effects
				(font
					(size 1.016 1.016)
					(thickness 0.1524)
				)
				(justify mirror)
			)
		)
		(duplicate_pad_numbers_are_jumpers no)
		(fp_line
			(start 0.508 -0.9398)
			(end 0.508 0.9398)
			(stroke
				(width 0.1524)
				(type default)
			)
			(layer "B.SilkS")
		)
		(fp_line
			(start -0.508 -0.9398)
			(end 0.508 -0.9398)
			(stroke
				(width 0.1524)
				(type default)
			)
			(layer "B.SilkS")
		)
		(fp_rect
			(start 0.508 0.9398)
			(end -0.508 -0.9398)
			(stroke
				(width 0)
				(type default)
			)
			(fill no)
			(layer "B.CrtYd")
		)
		(fp_rect
			(start 0.508 0.9398)
			(end -0.508 -0.9398)
			(stroke
				(width 0)
				(type default)
			)
			(fill no)
			(layer "B.Fab")
		)
		(pad "1" smd custom
			(at 0 -0.4445)
			(size 0.1397 0.1397)
			(layers "B.Cu" "B.Mask" "B.Paste")
			(net "CLK_50M_BMC_NCSI")
			(options
				(clearance outline)
				(anchor circle)
			)
			(primitives
				(gr_poly
					(pts
						(arc
							(start -0.1778 0.2794)
							(mid -0.249642 0.249642)
							(end -0.2794 0.1778)
						)
						(arc
							(start -0.2794 -0.1778)
							(mid -0.249642 -0.249642)
							(end -0.1778 -0.2794)
						)
						(arc
							(start 0.1778 -0.2794)
							(mid 0.249642 -0.249642)
							(end 0.2794 -0.1778)
						)
						(arc
							(start 0.2794 0.1778)
							(mid 0.249642 0.249642)
							(end 0.1778 0.2794)
						)
					)
					(width 0)
					(fill yes)
				)
			)
		)
		(pad "2" smd custom
			(at 0 0.4445)
			(size 0.1397 0.1397)
			(layers "B.Cu" "B.Mask" "B.Paste")
			(net "CLK_50M_BMC_NCSI_R")
			(options
				(clearance outline)
				(anchor circle)
			)
			(primitives
				(gr_poly
					(pts
						(arc
							(start -0.1778 0.2794)
							(mid -0.249642 0.249642)
							(end -0.2794 0.1778)
						)
						(arc
							(start -0.2794 -0.1778)
							(mid -0.249642 -0.249642)
							(end -0.1778 -0.2794)
						)
						(arc
							(start 0.1778 -0.2794)
							(mid 0.249642 -0.249642)
							(end 0.2794 -0.1778)
						)
						(arc
							(start 0.2794 0.1778)
							(mid 0.249642 0.249642)
							(end 0.1778 0.2794)
						)
					)
					(width 0)
					(fill yes)
				)
			)
		)
	)
	(footprint ""
		(layer "B.Cu")
		(at 226.740212 -193.911474)
		(property "Reference" "C3205"
			(at 0 0 0)
			(layer "B.SilkS")
			(hide yes)
			(effects
				(font
					(size 1.27 1.27)
				)
				(justify mirror)
			)
		)
		(property "Value" "SCD1U25V2KX-2-GP"
			(at -1.1811 -2.7051 0)
			(unlocked yes)
			(layer "B.Fab")
			(hide yes)
			(effects
				(font
					(size 1.016 1.016)
					(thickness 0.1524)
				)
				(justify mirror)
			)
		)
		(property "Device Type" "C402H22"
			(at -1.1811 -4.2291 0)
			(unlocked yes)
			(layer "B.Fab")
			(hide yes)
			(effects
				(font
					(size 1.016 1.016)
					(thickness 0.1524)
				)
				(justify mirror)
			)
		)
		(duplicate_pad_numbers_are_jumpers no)
		(fp_rect
			(start 0.4318 0.9525)
			(end -0.4318 -0.9525)
			(stroke
				(width 0)
				(type default)
			)
			(fill no)
			(layer "B.CrtYd")
		)
		(fp_rect
			(start 0.4318 0.9525)
			(end -0.4318 -0.9525)
			(stroke
				(width 0)
				(type default)
			)
			(fill no)
			(layer "B.Fab")
		)
		(pad "1" smd custom
			(at 0 -0.4445 180)
			(size 0.1524 0.1524)
			(layers "B.Cu" "B.Mask" "B.Paste")
			(net "P3V3_STBY")
			(options
				(clearance outline)
				(anchor circle)
			)
			(primitives
				(gr_poly
					(pts
						(arc
							(start 0.3048 0.2032)
							(mid 0.275042 0.275042)
							(end 0.2032 0.3048)
						)
						(arc
							(start -0.2032 0.3048)
							(mid -0.275042 0.275042)
							(end -0.3048 0.2032)
						)
						(arc
							(start -0.3048 -0.2032)
							(mid -0.275042 -0.275042)
							(end -0.2032 -0.3048)
						)
						(arc
							(start 0.2032 -0.3048)
							(mid 0.275042 -0.275042)
							(end 0.3048 -0.2032)
						)
					)
					(width 0)
					(fill yes)
				)
			)
		)
		(pad "2" smd custom
			(at 0 0.4445 180)
			(size 0.1524 0.1524)
			(layers "B.Cu" "B.Mask" "B.Paste")
			(net "GND")
			(options
				(clearance outline)
				(anchor circle)
			)
			(primitives
				(gr_poly
					(pts
						(arc
							(start 0.3048 0.2032)
							(mid 0.275042 0.275042)
							(end 0.2032 0.3048)
						)
						(arc
							(start -0.2032 0.3048)
							(mid -0.275042 0.275042)
							(end -0.3048 0.2032)
						)
						(arc
							(start -0.3048 -0.2032)
							(mid -0.275042 -0.275042)
							(end -0.2032 -0.3048)
						)
						(arc
							(start 0.2032 -0.3048)
							(mid 0.275042 -0.275042)
							(end 0.3048 -0.2032)
						)
					)
					(width 0)
					(fill yes)
				)
			)
		)
	)
	(footprint ""
		(layer "B.Cu")
		(at 146.414236 -61.79058 90)
		(property "Reference" "PR177"
			(at 0 0 90)
			(layer "B.SilkS")
			(hide yes)
			(effects
				(font
					(size 1.27 1.27)
				)
				(justify mirror)
			)
		)
		(property "Value" "0R3J-0-U-GP"
			(at 0.0254 -2.5146 90)
			(unlocked yes)
			(layer "B.Fab")
			(hide yes)
			(effects
				(font
					(size 1.016 1.016)
					(thickness 0.1524)
				)
				(justify mirror)
			)
		)
		(property "Device Type" "R603H22"
			(at 0.0254 -4.0386 90)
			(unlocked yes)
			(layer "B.Fab")
			(hide yes)
			(effects
				(font
					(size 1.016 1.016)
					(thickness 0.1524)
				)
				(justify mirror)
			)
		)
		(duplicate_pad_numbers_are_jumpers no)
		(fp_line
			(start 0.4826 0)
			(end 0.2032 0)
			(stroke
				(width 0.2032)
				(type default)
			)
			(layer "B.SilkS")
		)
		(fp_line
			(start -0.2032 0)
			(end -0.4826 0)
			(stroke
				(width 0.2032)
				(type default)
			)
			(layer "B.SilkS")
		)
		(fp_rect
			(start 0.5842 1.3335)
			(end -0.5842 -1.3335)
			(stroke
				(width 0)
				(type default)
			)
			(fill no)
			(layer "B.CrtYd")
		)
		(fp_rect
			(start 0.5842 1.3335)
			(end -0.5842 -1.3335)
			(stroke
				(width 0)
				(type default)
			)
			(fill no)
			(layer "B.Fab")
		)
		(pad "1" smd custom
			(at 0 -0.762 270)
			(size 0.2159 0.2159)
			(layers "B.Cu" "B.Mask" "B.Paste")
			(net "P12V")
			(options
				(clearance outline)
				(anchor circle)
			)
			(primitives
				(gr_poly
					(pts
						(arc
							(start -0.3302 0.4318)
							(mid -0.402042 0.402042)
							(end -0.4318 0.3302)
						)
						(arc
							(start -0.4318 -0.3302)
							(mid -0.402042 -0.402042)
							(end -0.3302 -0.4318)
						)
						(arc
							(start 0.3302 -0.4318)
							(mid 0.402042 -0.402042)
							(end 0.4318 -0.3302)
						)
						(arc
							(start 0.4318 0.3302)
							(mid 0.402042 0.402042)
							(end 0.3302 0.4318)
						)
					)
					(width 0)
					(fill yes)
				)
			)
		)
		(pad "2" smd custom
			(at 0 0.762 270)
			(size 0.2159 0.2159)
			(layers "B.Cu" "B.Mask" "B.Paste")
			(net "P0V9_VDD")
			(options
				(clearance outline)
				(anchor circle)
			)
			(primitives
				(gr_poly
					(pts
						(arc
							(start -0.3302 0.4318)
							(mid -0.402042 0.402042)
							(end -0.4318 0.3302)
						)
						(arc
							(start -0.4318 -0.3302)
							(mid -0.402042 -0.402042)
							(end -0.3302 -0.4318)
						)
						(arc
							(start 0.3302 -0.4318)
							(mid 0.402042 -0.402042)
							(end 0.4318 -0.3302)
						)
						(arc
							(start 0.4318 0.3302)
							(mid 0.402042 0.402042)
							(end 0.3302 0.4318)
						)
					)
					(width 0)
					(fill yes)
				)
			)
		)
	)
)
